(kicad_pcb
	(version 20260206)
	(generator "pcbnew")
	(generator_version "10.0")
	(general
		(thickness 1.6)
		(legacy_teardrops no)
	)
	(paper "A4")
	(title_block
		(title "peb — Lightning_PEB_BRD.brd")
		(comment 1 "Lightning (Wiwynn / Facebook NVMe JBOF) / footprints 1625-1631 of 2563")
	)
	(layers
		(0 "F.Cu" signal "TOP")
		(4 "In1.Cu" signal "L2GND")
		(6 "In2.Cu" signal "L3")
		(8 "In3.Cu" signal "L4VCC")
		(10 "In4.Cu" signal "L5VCC")
		(12 "In5.Cu" signal "L6")
		(14 "In6.Cu" signal "L7GND")
		(2 "B.Cu" signal "BOTTOM")
		(9 "F.Adhes" user "F.Adhesive")
		(11 "B.Adhes" user "B.Adhesive")
		(13 "F.Paste" user "Package Geometry/Pastemask Top")
		(15 "B.Paste" user "Package Geometry/Pastemask Bottom")
		(5 "F.SilkS" user "Ref Des/Silkscreen Top")
		(7 "B.SilkS" user "Ref Des/Silkscreen Bottom")
		(1 "F.Mask" user "Board Geometry/Soldermask Top")
		(3 "B.Mask" user "Board Geometry/Soldermask Bottom")
		(17 "Dwgs.User" user "User.Drawings")
		(19 "Cmts.User" user "User.Comments")
		(21 "Eco1.User" user "User.Eco1")
		(23 "Eco2.User" user "User.Eco2")
		(25 "Edge.Cuts" user "Board Geometry/Outline")
		(27 "Margin" user)
		(31 "F.CrtYd" user "Package Geometry/Place Bound Top")
		(29 "B.CrtYd" user "Package Geometry/Place Bound Bottom")
		(35 "F.Fab" user "Ref Des/Assembly Top")
		(33 "B.Fab" user "Ref Des/Assembly Bottom")
	)
	(footprint ""
		(layer "F.Cu")
		(at 119.4816 -24.3078)
		(property "Reference" "U54"
			(at 0 0 0)
			(layer "F.SilkS")
			(hide yes)
			(effects
				(font
					(size 1.27 1.27)
				)
			)
		)
		(property "Value" "TCA9554PWR-GP"
			(at 0.127 -12.573 0)
			(unlocked yes)
			(layer "F.Fab")
			(hide yes)
			(effects
				(font
					(size 1.016 1.016)
					(thickness 0.1524)
				)
			)
		)
		(property "Device Type" "TSOIC16H48"
			(at 0.1016 -14.5796 0)
			(unlocked yes)
			(layer "F.Fab")
			(hide yes)
			(effects
				(font
					(size 1.016 1.016)
					(thickness 0.1524)
				)
			)
		)
		(duplicate_pad_numbers_are_jumpers no)
		(fp_line
			(start -3.0988 -1.778)
			(end -3.0988 1.778)
			(stroke
				(width 0.1524)
				(type default)
			)
			(layer "F.SilkS")
		)
		(fp_line
			(start -3.0988 -1.778)
			(end 2.3622 -1.778)
			(stroke
				(width 0.1524)
				(type default)
			)
			(layer "F.SilkS")
		)
		(fp_line
			(start -2.921 3.81)
			(end -2.921 1.778)
			(stroke
				(width 0.508)
				(type default)
			)
			(layer "F.SilkS")
		)
		(fp_line
			(start -2.54 0)
			(end -3.0988 -0.5588)
			(stroke
				(width 0.1524)
				(type default)
			)
			(layer "F.SilkS")
		)
		(fp_line
			(start -2.54 0)
			(end -3.0988 0.5588)
			(stroke
				(width 0.1524)
				(type default)
			)
			(layer "F.SilkS")
		)
		(fp_line
			(start 2.3622 -1.778)
			(end 2.3622 1.778)
			(stroke
				(width 0.1524)
				(type default)
			)
			(layer "F.SilkS")
		)
		(fp_line
			(start 2.3622 1.778)
			(end -2.921 1.778)
			(stroke
				(width 0.1524)
				(type default)
			)
			(layer "F.SilkS")
		)
		(fp_poly
			(pts
				(xy -2.4638 -1.778) (xy -2.4638 1.778) (xy 2.3622 1.778) (xy 2.3622 -1.778)
			)
			(stroke
				(width 0)
				(type default)
			)
			(fill yes)
			(layer "F.SilkS")
		)
		(fp_rect
			(start -3.175 4.064)
			(end 3.175 -4.064)
			(stroke
				(width 0)
				(type default)
			)
			(fill no)
			(layer "F.CrtYd")
		)
		(fp_poly
			(pts
				(xy -3.175 -4.064) (xy 3.175 -4.064) (xy 3.175 4.064) (xy -3.175 4.064)
			)
			(stroke
				(width 0)
				(type default)
			)
			(fill no)
			(layer "F.Fab")
		)
		(pad "1" smd rect
			(at -2.27584 2.8194)
			(size 0.3556 1.524)
			(layers "F.Cu" "F.Mask" "F.Paste")
			(net "U54_A0")
		)
		(pad "2" smd rect
			(at -1.6256 2.8194)
			(size 0.3556 1.524)
			(layers "F.Cu" "F.Mask" "F.Paste")
			(net "U54_A1")
		)
		(pad "3" smd rect
			(at -0.97536 2.8194)
			(size 0.3556 1.524)
			(layers "F.Cu" "F.Mask" "F.Paste")
			(net "U54_A2")
		)
		(pad "4" smd rect
			(at -0.32512 2.8194)
			(size 0.3556 1.524)
			(layers "F.Cu" "F.Mask" "F.Paste")
			(net "U54_P0")
		)
		(pad "5" smd rect
			(at 0.32512 2.8194)
			(size 0.3556 1.524)
			(layers "F.Cu" "F.Mask" "F.Paste")
			(net "Net_37")
		)
		(pad "6" smd rect
			(at 0.97536 2.8194)
			(size 0.3556 1.524)
			(layers "F.Cu" "F.Mask" "F.Paste")
			(net "Net_38")
		)
		(pad "7" smd rect
			(at 1.6256 2.8194)
			(size 0.3556 1.524)
			(layers "F.Cu" "F.Mask" "F.Paste")
			(net "Net_39")
		)
		(pad "8" smd rect
			(at 2.27584 2.8194)
			(size 0.3556 1.524)
			(layers "F.Cu" "F.Mask" "F.Paste")
			(net "GND")
		)
		(pad "9" smd rect
			(at 2.27584 -2.8194)
			(size 0.3556 1.524)
			(layers "F.Cu" "F.Mask" "F.Paste")
			(net "Net_40")
		)
		(pad "10" smd rect
			(at 1.6256 -2.8194)
			(size 0.3556 1.524)
			(layers "F.Cu" "F.Mask" "F.Paste")
			(net "Net_109")
		)
		(pad "11" smd rect
			(at 0.97536 -2.8194)
			(size 0.3556 1.524)
			(layers "F.Cu" "F.Mask" "F.Paste")
			(net "Net_110")
		)
		(pad "12" smd rect
			(at 0.32512 -2.8194)
			(size 0.3556 1.524)
			(layers "F.Cu" "F.Mask" "F.Paste")
			(net "Net_111")
		)
		(pad "13" smd rect
			(at -0.32512 -2.8194)
			(size 0.3556 1.524)
			(layers "F.Cu" "F.Mask" "F.Paste")
			(net "U54_INT_N")
		)
		(pad "14" smd rect
			(at -0.97536 -2.8194)
			(size 0.3556 1.524)
			(layers "F.Cu" "F.Mask" "F.Paste")
			(net "U54_SCL")
		)
		(pad "15" smd rect
			(at -1.6256 -2.8194)
			(size 0.3556 1.524)
			(layers "F.Cu" "F.Mask" "F.Paste")
			(net "U54_SDA")
		)
		(pad "16" smd rect
			(at -2.27584 -2.8194)
			(size 0.3556 1.524)
			(layers "F.Cu" "F.Mask" "F.Paste")
			(net "P3V3_STBY")
		)
	)
	(footprint ""
		(layer "F.Cu")
		(at 102.208076 -212.420454 180)
		(property "Reference" "C150"
			(at 0 0 180)
			(layer "F.SilkS")
			(hide yes)
			(effects
				(font
					(size 1.27 1.27)
				)
			)
		)
		(property "Value" "SCD22U10V2KX-1GP"
			(at 1.1811 -2.7051 180)
			(unlocked yes)
			(layer "F.Fab")
			(hide yes)
			(effects
				(font
					(size 1.016 1.016)
					(thickness 0.1524)
				)
			)
		)
		(property "Device Type" "C402H22"
			(at 1.1811 -4.2291 180)
			(unlocked yes)
			(layer "F.Fab")
			(hide yes)
			(effects
				(font
					(size 1.016 1.016)
					(thickness 0.1524)
				)
			)
		)
		(duplicate_pad_numbers_are_jumpers no)
		(fp_rect
			(start -0.4318 0.9525)
			(end 0.4318 -0.9525)
			(stroke
				(width 0)
				(type default)
			)
			(fill no)
			(layer "F.CrtYd")
		)
		(fp_rect
			(start -0.4318 0.9525)
			(end 0.4318 -0.9525)
			(stroke
				(width 0)
				(type default)
			)
			(fill no)
			(layer "F.Fab")
		)
		(pad "1" smd custom
			(at 0 -0.4445 180)
			(size 0.1524 0.1524)
			(layers "F.Cu" "F.Mask" "F.Paste")
			(net "PCIE_TX_CAP_N62")
			(options
				(clearance outline)
				(anchor circle)
			)
			(primitives
				(gr_poly
					(pts
						(arc
							(start 0.3048 -0.2032)
							(mid 0.275042 -0.275042)
							(end 0.2032 -0.3048)
						)
						(arc
							(start -0.2032 -0.3048)
							(mid -0.275042 -0.275042)
							(end -0.3048 -0.2032)
						)
						(arc
							(start -0.3048 0.2032)
							(mid -0.275042 0.275042)
							(end -0.2032 0.3048)
						)
						(arc
							(start 0.2032 0.3048)
							(mid 0.275042 0.275042)
							(end 0.3048 0.2032)
						)
					)
					(width 0)
					(fill yes)
				)
			)
		)
		(pad "2" smd custom
			(at 0 0.4445 180)
			(size 0.1524 0.1524)
			(layers "F.Cu" "F.Mask" "F.Paste")
			(net "PCIE_TX_N62")
			(options
				(clearance outline)
				(anchor circle)
			)
			(primitives
				(gr_poly
					(pts
						(arc
							(start 0.3048 -0.2032)
							(mid 0.275042 -0.275042)
							(end 0.2032 -0.3048)
						)
						(arc
							(start -0.2032 -0.3048)
							(mid -0.275042 -0.275042)
							(end -0.3048 -0.2032)
						)
						(arc
							(start -0.3048 0.2032)
							(mid -0.275042 0.275042)
							(end -0.2032 0.3048)
						)
						(arc
							(start 0.2032 0.3048)
							(mid 0.275042 0.275042)
							(end 0.3048 0.2032)
						)
					)
					(width 0)
					(fill yes)
				)
			)
		)
	)
	(footprint ""
		(layer "F.Cu")
		(at 64.135 -45.649388 90)
		(property "Reference" "PC21"
			(at 0 0 90)
			(layer "F.SilkS")
			(hide yes)
			(effects
				(font
					(size 1.27 1.27)
				)
			)
		)
		(property "Value" "SC10U25V5KX-GP"
			(at -0.0762 -6.1214 90)
			(unlocked yes)
			(layer "F.Fab")
			(hide yes)
			(effects
				(font
					(size 1.016 1.016)
					(thickness 0.1524)
				)
			)
		)
		(property "Device Type" "C805H56"
			(at -0.0762 -8.1534 90)
			(unlocked yes)
			(layer "F.Fab")
			(hide yes)
			(effects
				(font
					(size 1.016 1.016)
					(thickness 0.1524)
				)
			)
		)
		(duplicate_pad_numbers_are_jumpers no)
		(fp_line
			(start 0.635 0)
			(end -0.635 0)
			(stroke
				(width 0.508)
				(type default)
			)
			(layer "F.SilkS")
		)
		(fp_rect
			(start -0.9652 1.778)
			(end 0.9652 -1.778)
			(stroke
				(width 0)
				(type default)
			)
			(fill no)
			(layer "F.CrtYd")
		)
		(fp_poly
			(pts
				(xy -0.9652 -1.778) (xy 0.9652 -1.778) (xy 0.9652 1.778) (xy -0.9652 1.778)
			)
			(stroke
				(width 0)
				(type default)
			)
			(fill no)
			(layer "F.Fab")
		)
		(pad "1" smd rect
			(at 0 -0.9652 90)
			(size 1.397 1.143)
			(layers "F.Cu" "F.Mask" "F.Paste")
			(net "P3V3_STBY_VIN")
		)
		(pad "2" smd rect
			(at 0 0.9652 90)
			(size 1.397 1.143)
			(layers "F.Cu" "F.Mask" "F.Paste")
			(net "GND")
		)
	)
	(footprint ""
		(layer "F.Cu")
		(at 53.721 -124.46 -90)
		(property "Reference" "R804"
			(at 0 0 270)
			(layer "F.SilkS")
			(hide yes)
			(effects
				(font
					(size 1.27 1.27)
				)
			)
		)
		(property "Value" "4K7R2F-GP"
			(at 0.064008 -3.993896 270)
			(unlocked yes)
			(layer "F.Fab")
			(hide yes)
			(effects
				(font
					(size 1.016 1.016)
					(thickness 0.1524)
				)
			)
		)
		(property "Device Type" "R402H16"
			(at 0.064008 -5.517896 270)
			(unlocked yes)
			(layer "F.Fab")
			(hide yes)
			(effects
				(font
					(size 1.016 1.016)
					(thickness 0.1524)
				)
			)
		)
		(duplicate_pad_numbers_are_jumpers no)
		(fp_line
			(start -0.508 -0.9398)
			(end -0.508 0.9398)
			(stroke
				(width 0.1524)
				(type default)
			)
			(layer "F.SilkS")
		)
		(fp_line
			(start 0.508 -0.9398)
			(end -0.508 -0.9398)
			(stroke
				(width 0.1524)
				(type default)
			)
			(layer "F.SilkS")
		)
		(fp_rect
			(start -0.508 0.9398)
			(end 0.508 -0.9398)
			(stroke
				(width 0)
				(type default)
			)
			(fill no)
			(layer "F.CrtYd")
		)
		(fp_rect
			(start -0.508 0.9398)
			(end 0.508 -0.9398)
			(stroke
				(width 0)
				(type default)
			)
			(fill no)
			(layer "F.Fab")
		)
		(pad "1" smd custom
			(at 0 -0.4445 270)
			(size 0.1397 0.1397)
			(layers "F.Cu" "F.Mask" "F.Paste")
			(net "P3V3_STBY")
			(options
				(clearance outline)
				(anchor circle)
			)
			(primitives
				(gr_poly
					(pts
						(arc
							(start -0.1778 -0.2794)
							(mid -0.249642 -0.249642)
							(end -0.2794 -0.1778)
						)
						(arc
							(start -0.2794 0.1778)
							(mid -0.249642 0.249642)
							(end -0.1778 0.2794)
						)
						(arc
							(start 0.1778 0.2794)
							(mid 0.249642 0.249642)
							(end 0.2794 0.1778)
						)
						(arc
							(start 0.2794 -0.1778)
							(mid 0.249642 -0.249642)
							(end 0.1778 -0.2794)
						)
					)
					(width 0)
					(fill yes)
				)
			)
		)
		(pad "2" smd custom
			(at 0 0.4445 270)
			(size 0.1397 0.1397)
			(layers "F.Cu" "F.Mask" "F.Paste")
			(net "JTAG_BMC_TCK")
			(options
				(clearance outline)
				(anchor circle)
			)
			(primitives
				(gr_poly
					(pts
						(arc
							(start -0.1778 -0.2794)
							(mid -0.249642 -0.249642)
							(end -0.2794 -0.1778)
						)
						(arc
							(start -0.2794 0.1778)
							(mid -0.249642 0.249642)
							(end -0.1778 0.2794)
						)
						(arc
							(start 0.1778 0.2794)
							(mid 0.249642 0.249642)
							(end 0.2794 0.1778)
						)
						(arc
							(start 0.2794 -0.1778)
							(mid 0.249642 -0.249642)
							(end 0.1778 -0.2794)
						)
					)
					(width 0)
					(fill yes)
				)
			)
		)
	)
	(footprint ""
		(layer "F.Cu")
		(at 34.166556 -94.99219 -90)
		(property "Reference" "R48"
			(at 0 0 270)
			(layer "F.SilkS")
			(hide yes)
			(effects
				(font
					(size 1.27 1.27)
				)
			)
		)
		(property "Value" "0R2J-2-GP"
			(at 0.064008 -3.993896 270)
			(unlocked yes)
			(layer "F.Fab")
			(hide yes)
			(effects
				(font
					(size 1.016 1.016)
					(thickness 0.1524)
				)
			)
		)
		(property "Device Type" "R402H16"
			(at 0.064008 -5.517896 270)
			(unlocked yes)
			(layer "F.Fab")
			(hide yes)
			(effects
				(font
					(size 1.016 1.016)
					(thickness 0.1524)
				)
			)
		)
		(duplicate_pad_numbers_are_jumpers no)
		(fp_line
			(start -0.508 -0.9398)
			(end -0.508 0.9398)
			(stroke
				(width 0.1524)
				(type default)
			)
			(layer "F.SilkS")
		)
		(fp_line
			(start 0.508 -0.9398)
			(end -0.508 -0.9398)
			(stroke
				(width 0.1524)
				(type default)
			)
			(layer "F.SilkS")
		)
		(fp_rect
			(start -0.508 0.9398)
			(end 0.508 -0.9398)
			(stroke
				(width 0)
				(type default)
			)
			(fill no)
			(layer "F.CrtYd")
		)
		(fp_rect
			(start -0.508 0.9398)
			(end 0.508 -0.9398)
			(stroke
				(width 0)
				(type default)
			)
			(fill no)
			(layer "F.Fab")
		)
		(pad "1" smd custom
			(at 0 -0.4445 270)
			(size 0.1397 0.1397)
			(layers "F.Cu" "F.Mask" "F.Paste")
			(net "NVM_SK_R")
			(options
				(clearance outline)
				(anchor circle)
			)
			(primitives
				(gr_poly
					(pts
						(arc
							(start -0.1778 -0.2794)
							(mid -0.249642 -0.249642)
							(end -0.2794 -0.1778)
						)
						(arc
							(start -0.2794 0.1778)
							(mid -0.249642 0.249642)
							(end -0.1778 0.2794)
						)
						(arc
							(start 0.1778 0.2794)
							(mid 0.249642 0.249642)
							(end 0.2794 0.1778)
						)
						(arc
							(start 0.2794 -0.1778)
							(mid 0.249642 -0.249642)
							(end 0.1778 -0.2794)
						)
					)
					(width 0)
					(fill yes)
				)
			)
		)
		(pad "2" smd custom
			(at 0 0.4445 270)
			(size 0.1397 0.1397)
			(layers "F.Cu" "F.Mask" "F.Paste")
			(net "I2C_MUX_2A")
			(options
				(clearance outline)
				(anchor circle)
			)
			(primitives
				(gr_poly
					(pts
						(arc
							(start -0.1778 -0.2794)
							(mid -0.249642 -0.249642)
							(end -0.2794 -0.1778)
						)
						(arc
							(start -0.2794 0.1778)
							(mid -0.249642 0.249642)
							(end -0.1778 0.2794)
						)
						(arc
							(start 0.1778 0.2794)
							(mid 0.249642 0.249642)
							(end 0.2794 0.1778)
						)
						(arc
							(start 0.2794 -0.1778)
							(mid 0.249642 -0.249642)
							(end 0.1778 -0.2794)
						)
					)
					(width 0)
					(fill yes)
				)
			)
		)
	)
	(footprint ""
		(layer "F.Cu")
		(at 39.243 -118.364)
		(property "Reference" "TP326"
			(at 0 0 0)
			(layer "F.SilkS")
			(hide yes)
			(effects
				(font
					(size 1.27 1.27)
				)
			)
		)
		(property "Value" "TPAD28-2-GP"
			(at -0.0127 -1.6637 0)
			(unlocked yes)
			(layer "F.Fab")
			(hide yes)
			(effects
				(font
					(size 1.016 1.016)
					(thickness 0.1524)
				)
			)
		)
		(property "Device Type" "TPAD28"
			(at -0.0127 -3.1877 0)
			(unlocked yes)
			(layer "F.Fab")
			(hide yes)
			(effects
				(font
					(size 1.016 1.016)
					(thickness 0.1524)
				)
			)
		)
		(duplicate_pad_numbers_are_jumpers no)
		(fp_poly
			(pts
				(arc
					(start 0.3556 0)
					(mid -0.3556 0)
					(end 0.3556 0)
				)
			)
			(stroke
				(width 0)
				(type default)
			)
			(fill no)
			(layer "F.CrtYd")
		)
		(fp_poly
			(pts
				(arc
					(start 0.6096 0)
					(mid -0.6096 0)
					(end 0.6096 0)
				)
			)
			(stroke
				(width 0)
				(type default)
			)
			(fill no)
			(layer "F.Fab")
		)
		(pad "1" smd circle
			(at 0 0)
			(size 0.7112 0.7112)
			(layers "F.Cu" "F.Mask" "F.Paste")
			(net "TP_GPIOU1")
		)
	)
	(footprint ""
		(layer "F.Cu")
		(at 27.7622 -51.6382 -90)
		(property "Reference" "C414"
			(at 0 0 270)
			(layer "F.SilkS")
			(hide yes)
			(effects
				(font
					(size 1.27 1.27)
				)
			)
		)
		(property "Value" "SCD1U16V2KX-3GP"
			(at 1.1811 -2.7051 270)
			(unlocked yes)
			(layer "F.Fab")
			(hide yes)
			(effects
				(font
					(size 1.016 1.016)
					(thickness 0.1524)
				)
			)
		)
		(property "Device Type" "C402H22"
			(at 1.1811 -4.2291 270)
			(unlocked yes)
			(layer "F.Fab")
			(hide yes)
			(effects
				(font
					(size 1.016 1.016)
					(thickness 0.1524)
				)
			)
		)
		(duplicate_pad_numbers_are_jumpers no)
		(fp_rect
			(start -0.4318 0.9525)
			(end 0.4318 -0.9525)
			(stroke
				(width 0)
				(type default)
			)
			(fill no)
			(layer "F.CrtYd")
		)
		(fp_rect
			(start -0.4318 0.9525)
			(end 0.4318 -0.9525)
			(stroke
				(width 0)
				(type default)
			)
			(fill no)
			(layer "F.Fab")
		)
		(pad "1" smd custom
			(at 0 -0.4445 270)
			(size 0.1524 0.1524)
			(layers "F.Cu" "F.Mask" "F.Paste")
			(net "LED_MDI0_1G_N_R")
			(options
				(clearance outline)
				(anchor circle)
			)
			(primitives
				(gr_poly
					(pts
						(arc
							(start 0.3048 -0.2032)
							(mid 0.275042 -0.275042)
							(end 0.2032 -0.3048)
						)
						(arc
							(start -0.2032 -0.3048)
							(mid -0.275042 -0.275042)
							(end -0.3048 -0.2032)
						)
						(arc
							(start -0.3048 0.2032)
							(mid -0.275042 0.275042)
							(end -0.2032 0.3048)
						)
						(arc
							(start 0.2032 0.3048)
							(mid 0.275042 0.275042)
							(end 0.3048 0.2032)
						)
					)
					(width 0)
					(fill yes)
				)
			)
		)
		(pad "2" smd custom
			(at 0 0.4445 270)
			(size 0.1524 0.1524)
			(layers "F.Cu" "F.Mask" "F.Paste")
			(net "GND")
			(options
				(clearance outline)
				(anchor circle)
			)
			(primitives
				(gr_poly
					(pts
						(arc
							(start 0.3048 -0.2032)
							(mid 0.275042 -0.275042)
							(end 0.2032 -0.3048)
						)
						(arc
							(start -0.2032 -0.3048)
							(mid -0.275042 -0.275042)
							(end -0.3048 -0.2032)
						)
						(arc
							(start -0.3048 0.2032)
							(mid -0.275042 0.275042)
							(end -0.2032 0.3048)
						)
						(arc
							(start 0.2032 0.3048)
							(mid 0.275042 0.275042)
							(end 0.3048 0.2032)
						)
					)
					(width 0)
					(fill yes)
				)
			)
		)
	)
)
